# S9S_MB_2U (Grand Teton) — schematic netlist excerpt (pin names and nets, part order shuffled) for the footprints in the layout excerpt that follows; sources: Cadence DE-HDL packaged netlist, KiCad conversion of 03242023_DA0F0TMBIJ0_F0T_Motherboard_J_brd_V01_OCP.brd

PC1869  Q_CAP  0.1UF 25V 10% X7R  pkg 0402  page 259 : A = P3V3_AUX ; B = GND
R4493  Q_RES  1 1% CHIP  pkg 0603LF  page 211 : A = P3V3_9ZXL045 ; B = P3V3_9ZXL045_VDDA

(kicad_pcb
	(version 20260206)
	(generator "pcbnew")
	(generator_version "10.0")
	(general
		(thickness 1.6)
		(legacy_teardrops no)
	)
	(paper "A4")
	(title_block
		(title "03242023_DA0F0TMBIJ0_F0T_Motherboard_J_brd_V01_OCP.brd")
		(comment 1 "Grand Teton / footprints 4356-4357 of 6105")
	)
	(layers
		(0 "F.Cu" signal "TOP")
		(4 "In1.Cu" signal "GND")
		(6 "In2.Cu" signal "IN1")
		(8 "In3.Cu" signal "GND1")
		(10 "In4.Cu" signal "IN2")
		(12 "In5.Cu" signal "GND2")
		(14 "In6.Cu" signal "IN3")
		(16 "In7.Cu" signal "GND3")
		(18 "In8.Cu" signal "VCC")
		(20 "In9.Cu" signal "VCC1")
		(22 "In10.Cu" signal "GND4")
		(24 "In11.Cu" signal "IN4")
		(26 "In12.Cu" signal "GND5")
		(28 "In13.Cu" signal "IN5")
		(30 "In14.Cu" signal "GND6")
		(32 "In15.Cu" signal "IN6")
		(34 "In16.Cu" signal "GND7")
		(2 "B.Cu" signal "BOTTOM")
		(9 "F.Adhes" user "F.Adhesive")
		(11 "B.Adhes" user "B.Adhesive")
		(13 "F.Paste" user "Package Geometry/Pastemask Top")
		(15 "B.Paste" user "Package Geometry/Pastemask Bottom")
		(5 "F.SilkS" user "Ref Des/Silkscreen Top")
		(7 "B.SilkS" user "Ref Des/Silkscreen Bottom")
		(1 "F.Mask" user "Board Geometry/Soldermask Top")
		(3 "B.Mask" user "Board Geometry/Soldermask Bottom")
		(17 "Dwgs.User" user "User.Drawings")
		(19 "Cmts.User" user "User.Comments")
		(21 "Eco1.User" user "User.Eco1")
		(23 "Eco2.User" user "User.Eco2")
		(25 "Edge.Cuts" user "Board Geometry/Outline")
		(27 "Margin" user)
		(31 "F.CrtYd" user "Package Geometry/Place Bound Top")
		(29 "B.CrtYd" user "Package Geometry/Place Bound Bottom")
		(35 "F.Fab" user "Ref Des/Assembly Top")
		(33 "B.Fab" user "Ref Des/Assembly Bottom")
	)
	(footprint ""
		(layer "B.Cu")
		(at 445.866012 -58.300112 -90)
		(property "Reference" "PC1869"
			(at 0 0 90)
			(layer "B.SilkS")
			(hide yes)
			(effects
				(font
					(size 1.27 1.27)
				)
				(justify mirror)
			)
		)
		(property "Value" ""
			(at 0 0 90)
			(layer "B.Fab")
			(effects
				(font
					(size 1.27 1.27)
				)
				(justify mirror)
			)
		)
		(duplicate_pad_numbers_are_jumpers no)
		(fp_line
			(start -0.7874 0.4064)
			(end 0.7874 0.4064)
			(stroke
				(width 0.1524)
				(type default)
			)
			(layer "B.SilkS")
		)
		(fp_line
			(start 0.7874 0.4064)
			(end 0.7874 -0.4064)
			(stroke
				(width 0.1524)
				(type default)
			)
			(layer "B.SilkS")
		)
		(fp_line
			(start -0.7874 -0.4064)
			(end -0.7874 0.4064)
			(stroke
				(width 0.1524)
				(type default)
			)
			(layer "B.SilkS")
		)
		(fp_line
			(start 0.7874 -0.4064)
			(end -0.7874 -0.4064)
			(stroke
				(width 0.1524)
				(type default)
			)
			(layer "B.SilkS")
		)
		(fp_line
			(start -0.67945 0.3048)
			(end -0.120396 0.3048)
			(stroke
				(width 0.1)
				(type default)
			)
			(layer "B.Fab")
		)
		(fp_line
			(start -0.120396 0.3048)
			(end -0.120396 0.2794)
			(stroke
				(width 0.1)
				(type default)
			)
			(layer "B.Fab")
		)
		(fp_line
			(start 0.12065 0.3048)
			(end 0.67945 0.3048)
			(stroke
				(width 0.1)
				(type default)
			)
			(layer "B.Fab")
		)
		(fp_line
			(start 0.67945 0.3048)
			(end 0.67945 -0.305054)
			(stroke
				(width 0.1)
				(type default)
			)
			(layer "B.Fab")
		)
		(fp_line
			(start -0.120396 0.2794)
			(end 0.12065 0.2794)
			(stroke
				(width 0.1)
				(type default)
			)
			(layer "B.Fab")
		)
		(fp_line
			(start 0.12065 0.2794)
			(end 0.12065 0.3048)
			(stroke
				(width 0.1)
				(type default)
			)
			(layer "B.Fab")
		)
		(fp_line
			(start -0.12065 -0.2794)
			(end -0.12065 -0.3048)
			(stroke
				(width 0.1)
				(type default)
			)
			(layer "B.Fab")
		)
		(fp_line
			(start 0.12065 -0.2794)
			(end -0.12065 -0.2794)
			(stroke
				(width 0.1)
				(type default)
			)
			(layer "B.Fab")
		)
		(fp_line
			(start -0.67945 -0.3048)
			(end -0.67945 0.3048)
			(stroke
				(width 0.1)
				(type default)
			)
			(layer "B.Fab")
		)
		(fp_line
			(start -0.12065 -0.3048)
			(end -0.67945 -0.3048)
			(stroke
				(width 0.1)
				(type default)
			)
			(layer "B.Fab")
		)
		(fp_line
			(start 0.12065 -0.305054)
			(end 0.12065 -0.2794)
			(stroke
				(width 0.1)
				(type default)
			)
			(layer "B.Fab")
		)
		(fp_line
			(start 0.67945 -0.305054)
			(end 0.12065 -0.305054)
			(stroke
				(width 0.1)
				(type default)
			)
			(layer "B.Fab")
		)
		(pad "1" smd circle
			(at 0.40005 0 90)
			(size 0 0)
			(layers "B.Cu" "B.Mask" "B.Paste")
			(net "P3V3_AUX")
		)
		(pad "2" smd circle
			(at -0.40005 0 90)
			(size 0 0)
			(layers "B.Cu" "B.Mask" "B.Paste")
			(net "GND")
		)
	)
	(footprint ""
		(layer "B.Cu")
		(at 108.42371 -417.069524 180)
		(property "Reference" "R4493"
			(at 0 0 0)
			(layer "B.SilkS")
			(hide yes)
			(effects
				(font
					(size 1.27 1.27)
				)
				(justify mirror)
			)
		)
		(property "Value" ""
			(at 0 0 0)
			(layer "B.Fab")
			(effects
				(font
					(size 1.27 1.27)
				)
				(justify mirror)
			)
		)
		(duplicate_pad_numbers_are_jumpers no)
		(fp_line
			(start 1.2954 0.5842)
			(end 1.2954 -0.5842)
			(stroke
				(width 0.1524)
				(type default)
			)
			(layer "B.SilkS")
		)
		(fp_line
			(start 1.2954 -0.5842)
			(end -1.2954 -0.5842)
			(stroke
				(width 0.1524)
				(type default)
			)
			(layer "B.SilkS")
		)
		(fp_line
			(start -1.2954 0.5842)
			(end 1.2954 0.5842)
			(stroke
				(width 0.1524)
				(type default)
			)
			(layer "B.SilkS")
		)
		(fp_line
			(start -1.2954 -0.5842)
			(end -1.2954 0.5842)
			(stroke
				(width 0.1524)
				(type default)
			)
			(layer "B.SilkS")
		)
		(fp_line
			(start 1.1938 0.4064)
			(end 1.1938 -0.406654)
			(stroke
				(width 0.1)
				(type default)
			)
			(layer "B.Fab")
		)
		(fp_line
			(start 1.1938 -0.406654)
			(end 0.8636 -0.406654)
			(stroke
				(width 0.1)
				(type default)
			)
			(layer "B.Fab")
		)
		(fp_line
			(start 0.8636 0.4572)
			(end 0.8636 0.4318)
			(stroke
				(width 0.1)
				(type default)
			)
			(layer "B.Fab")
		)
		(fp_line
			(start 0.8636 0.4318)
			(end 0.8636 0.4064)
			(stroke
				(width 0.1)
				(type default)
			)
			(layer "B.Fab")
		)
		(fp_line
			(start 0.8636 0.4064)
			(end 1.1938 0.4064)
			(stroke
				(width 0.1)
				(type default)
			)
			(layer "B.Fab")
		)
		(fp_line
			(start 0.8636 -0.406654)
			(end 0.8636 -0.4572)
			(stroke
				(width 0.1)
				(type default)
			)
			(layer "B.Fab")
		)
		(fp_line
			(start 0.8636 -0.4572)
			(end -0.8636 -0.4572)
			(stroke
				(width 0.1)
				(type default)
			)
			(layer "B.Fab")
		)
		(fp_line
			(start -0.8636 0.4572)
			(end 0.8636 0.4572)
			(stroke
				(width 0.1)
				(type default)
			)
			(layer "B.Fab")
		)
		(fp_line
			(start -0.8636 0.4064)
			(end -0.8636 0.4572)
			(stroke
				(width 0.1)
				(type default)
			)
			(layer "B.Fab")
		)
		(fp_line
			(start -0.8636 -0.406654)
			(end -1.1938 -0.406654)
			(stroke
				(width 0.1)
				(type default)
			)
			(layer "B.Fab")
		)
		(fp_line
			(start -0.8636 -0.4572)
			(end -0.8636 -0.406654)
			(stroke
				(width 0.1)
				(type default)
			)
			(layer "B.Fab")
		)
		(fp_line
			(start -1.1938 0.4064)
			(end -0.8636 0.4064)
			(stroke
				(width 0.1)
				(type default)
			)
			(layer "B.Fab")
		)
		(fp_line
			(start -1.1938 -0.406654)
			(end -1.1938 0.4064)
			(stroke
				(width 0.1)
				(type default)
			)
			(layer "B.Fab")
		)
		(pad "1" smd rect
			(at 0.7366 0 90)
			(size 0.7112 0.8128)
			(layers "B.Cu" "B.Mask" "B.Paste")
			(net "P3V3_9ZXL045")
		)
		(pad "2" smd rect
			(at -0.7366 0 90)
			(size 0.7112 0.8128)
			(layers "B.Cu" "B.Mask" "B.Paste")
			(net "P3V3_9ZXL045_VDDA")
		)
	)
)
